# T6G (Grand Teton) — schematic netlist excerpt (pin names and nets, part order shuffled) for the footprints in the layout excerpt that follows; sources: Cadence DE-HDL packaged netlist, KiCad conversion of 04192023_DAF0TMB3IC0_F0TG_MB_C_brd_V02_OCP.brd

R6083  Q_RES  4.7K 5% CHIP  pkg 0402LF  page 28 : A = PVDD11_S3_P0 ; B = SMB_CPU0_3_SCL
PC6627  Q_CAPP  470UF 2.5V 20% SPCAP  pkg SMLF  page 365 : A = P0V9_CPU1_RT_2D ; B = GND

(kicad_pcb
	(version 20260206)
	(generator "pcbnew")
	(generator_version "10.0")
	(general
		(thickness 1.6)
		(legacy_teardrops no)
	)
	(paper "A4")
	(title_block
		(title "04192023_DAF0TMB3IC0_F0TG_MB_C_brd_V02_OCP.brd")
		(comment 1 "Grand Teton / footprints 5353-5354 of 8354")
	)
	(layers
		(0 "F.Cu" signal "TOP")
		(4 "In1.Cu" signal "GND")
		(6 "In2.Cu" signal "IN1")
		(8 "In3.Cu" signal "GND1")
		(10 "In4.Cu" signal "IN2")
		(12 "In5.Cu" signal "GND2")
		(14 "In6.Cu" signal "IN3")
		(16 "In7.Cu" signal "GND3")
		(18 "In8.Cu" signal "VCC")
		(20 "In9.Cu" signal "VCC1")
		(22 "In10.Cu" signal "GND4")
		(24 "In11.Cu" signal "IN4")
		(26 "In12.Cu" signal "GND5")
		(28 "In13.Cu" signal "IN5")
		(30 "In14.Cu" signal "GND6")
		(32 "In15.Cu" signal "IN6")
		(34 "In16.Cu" signal "GND7")
		(2 "B.Cu" signal "BOTTOM")
		(9 "F.Adhes" user "F.Adhesive")
		(11 "B.Adhes" user "B.Adhesive")
		(13 "F.Paste" user "Package Geometry/Pastemask Top")
		(15 "B.Paste" user "Package Geometry/Pastemask Bottom")
		(5 "F.SilkS" user "Ref Des/Silkscreen Top")
		(7 "B.SilkS" user "Ref Des/Silkscreen Bottom")
		(1 "F.Mask" user "Board Geometry/Soldermask Top")
		(3 "B.Mask" user "Board Geometry/Soldermask Bottom")
		(17 "Dwgs.User" user "User.Drawings")
		(19 "Cmts.User" user "User.Comments")
		(21 "Eco1.User" user "User.Eco1")
		(23 "Eco2.User" user "User.Eco2")
		(25 "Edge.Cuts" user "Board Geometry/Outline")
		(27 "Margin" user)
		(31 "F.CrtYd" user "Package Geometry/Place Bound Top")
		(29 "B.CrtYd" user "Package Geometry/Place Bound Bottom")
		(35 "F.Fab" user "Ref Des/Assembly Top")
		(33 "B.Fab" user "Ref Des/Assembly Bottom")
	)
	(footprint ""
		(layer "B.Cu")
		(at 391.636758 -202.48499)
		(property "Reference" "R6083"
			(at 0 0 0)
			(layer "B.SilkS")
			(hide yes)
			(effects
				(font
					(size 1.27 1.27)
				)
				(justify mirror)
			)
		)
		(property "Value" ""
			(at 0 0 0)
			(layer "B.Fab")
			(effects
				(font
					(size 1.27 1.27)
				)
				(justify mirror)
			)
		)
		(duplicate_pad_numbers_are_jumpers no)
		(fp_line
			(start -0.7874 -0.4064)
			(end -0.7874 0.4064)
			(stroke
				(width 0.1524)
				(type default)
			)
			(layer "B.SilkS")
		)
		(fp_line
			(start -0.7874 0.4064)
			(end 0.7874 0.4064)
			(stroke
				(width 0.1524)
				(type default)
			)
			(layer "B.SilkS")
		)
		(fp_line
			(start 0.7874 -0.4064)
			(end -0.7874 -0.4064)
			(stroke
				(width 0.1524)
				(type default)
			)
			(layer "B.SilkS")
		)
		(fp_line
			(start 0.7874 0.4064)
			(end 0.7874 -0.4064)
			(stroke
				(width 0.1524)
				(type default)
			)
			(layer "B.SilkS")
		)
		(fp_line
			(start -0.67945 -0.3048)
			(end -0.67945 0.3048)
			(stroke
				(width 0.1)
				(type default)
			)
			(layer "B.Fab")
		)
		(fp_line
			(start -0.67945 0.3048)
			(end -0.120396 0.3048)
			(stroke
				(width 0.1)
				(type default)
			)
			(layer "B.Fab")
		)
		(fp_line
			(start -0.12065 -0.3048)
			(end -0.67945 -0.3048)
			(stroke
				(width 0.1)
				(type default)
			)
			(layer "B.Fab")
		)
		(fp_line
			(start -0.12065 -0.2794)
			(end -0.12065 -0.3048)
			(stroke
				(width 0.1)
				(type default)
			)
			(layer "B.Fab")
		)
		(fp_line
			(start -0.120396 0.2794)
			(end 0.12065 0.2794)
			(stroke
				(width 0.1)
				(type default)
			)
			(layer "B.Fab")
		)
		(fp_line
			(start -0.120396 0.3048)
			(end -0.120396 0.2794)
			(stroke
				(width 0.1)
				(type default)
			)
			(layer "B.Fab")
		)
		(fp_line
			(start 0.12065 -0.305054)
			(end 0.12065 -0.2794)
			(stroke
				(width 0.1)
				(type default)
			)
			(layer "B.Fab")
		)
		(fp_line
			(start 0.12065 -0.2794)
			(end -0.12065 -0.2794)
			(stroke
				(width 0.1)
				(type default)
			)
			(layer "B.Fab")
		)
		(fp_line
			(start 0.12065 0.2794)
			(end 0.12065 0.3048)
			(stroke
				(width 0.1)
				(type default)
			)
			(layer "B.Fab")
		)
		(fp_line
			(start 0.12065 0.3048)
			(end 0.67945 0.3048)
			(stroke
				(width 0.1)
				(type default)
			)
			(layer "B.Fab")
		)
		(fp_line
			(start 0.67945 -0.305054)
			(end 0.12065 -0.305054)
			(stroke
				(width 0.1)
				(type default)
			)
			(layer "B.Fab")
		)
		(fp_line
			(start 0.67945 0.3048)
			(end 0.67945 -0.305054)
			(stroke
				(width 0.1)
				(type default)
			)
			(layer "B.Fab")
		)
		(pad "1" smd circle
			(at 0.40005 0 180)
			(size 0 0)
			(layers "B.Cu" "B.Mask" "B.Paste")
			(net "PVDD11_S3_P0")
		)
		(pad "2" smd circle
			(at -0.40005 0 180)
			(size 0 0)
			(layers "B.Cu" "B.Mask" "B.Paste")
			(net "SMB_CPU0_3_SCL")
		)
	)
	(footprint ""
		(layer "B.Cu")
		(at 18.841974 -373.339614 90)
		(property "Reference" "PC6627"
			(at -3.642614 -2.993644 270)
			(unlocked yes)
			(layer "B.SilkS")
			(effects
				(font
					(size 0.7874 0.5842)
					(thickness 0.1524)
				)
				(justify left mirror)
			)
		)
		(property "Value" ""
			(at 0 0 90)
			(layer "B.Fab")
			(effects
				(font
					(size 1.27 1.27)
				)
				(justify mirror)
			)
		)
		(duplicate_pad_numbers_are_jumpers no)
		(fp_line
			(start 4.84378 -2.150618)
			(end 4.53898 -2.150618)
			(stroke
				(width 0.1524)
				(type default)
			)
			(layer "B.SilkS")
		)
		(fp_line
			(start 4.84378 -2.150618)
			(end 4.842256 2.163064)
			(stroke
				(width 0.1524)
				(type default)
			)
			(layer "B.SilkS")
		)
		(fp_line
			(start 4.69138 -2.150618)
			(end 4.692396 2.161032)
			(stroke
				(width 0.1524)
				(type default)
			)
			(layer "B.SilkS")
		)
		(fp_line
			(start 4.53898 -2.150618)
			(end 4.539742 2.152142)
			(stroke
				(width 0.1524)
				(type default)
			)
			(layer "B.SilkS")
		)
		(fp_line
			(start 4.53898 -2.15011)
			(end -4.53898 -2.15011)
			(stroke
				(width 0.1524)
				(type default)
			)
			(layer "B.SilkS")
		)
		(fp_line
			(start -4.53898 -2.15011)
			(end -4.53898 2.15011)
			(stroke
				(width 0.1524)
				(type default)
			)
			(layer "B.SilkS")
		)
		(fp_line
			(start 4.53898 2.15011)
			(end 4.53898 -2.15011)
			(stroke
				(width 0.1524)
				(type default)
			)
			(layer "B.SilkS")
		)
		(fp_line
			(start -4.53898 2.15011)
			(end 4.53898 2.15011)
			(stroke
				(width 0.1524)
				(type default)
			)
			(layer "B.SilkS")
		)
		(fp_line
			(start 4.83108 2.150364)
			(end 4.447794 2.149348)
			(stroke
				(width 0.1524)
				(type default)
			)
			(layer "B.SilkS")
		)
		(fp_line
			(start 3.64998 -2.15011)
			(end -3.64998 -2.15011)
			(stroke
				(width 0.1)
				(type default)
			)
			(layer "B.Fab")
		)
		(fp_line
			(start -3.64998 -2.15011)
			(end -3.64998 2.15011)
			(stroke
				(width 0.1)
				(type default)
			)
			(layer "B.Fab")
		)
		(fp_line
			(start 3.64998 2.15011)
			(end 3.64998 -2.15011)
			(stroke
				(width 0.1)
				(type default)
			)
			(layer "B.Fab")
		)
		(fp_line
			(start -3.64998 2.15011)
			(end 3.64998 2.15011)
			(stroke
				(width 0.1)
				(type default)
			)
			(layer "B.Fab")
		)
		(fp_text user "+"
			(at 6.338824 -1.180084 90)
			(unlocked yes)
			(layer "B.SilkS")
			(effects
				(font
					(size 1.905 1.4224)
					(thickness 0.1524)
				)
				(justify left mirror)
			)
		)
		(fp_text user "-"
			(at -4.313174 -0.094488 90)
			(unlocked yes)
			(layer "B.SilkS")
			(effects
				(font
					(size 1.905 1.4224)
					(thickness 0.1524)
				)
				(justify left mirror)
			)
		)
		(fp_text user "+"
			(at 6.214872 -0.337058 90)
			(unlocked yes)
			(layer "B.Fab")
			(effects
				(font
					(size 1.905 1.4224)
					(thickness 0.1524)
				)
				(justify left mirror)
			)
		)
		(fp_text user "-"
			(at -4.313174 -0.094488 90)
			(unlocked yes)
			(layer "B.Fab")
			(effects
				(font
					(size 1.905 1.4224)
					(thickness 0.1524)
				)
				(justify left mirror)
			)
		)
		(pad "1" smd rect
			(at 3.199892 0 270)
			(size 2.413 2.8194)
			(layers "B.Cu" "B.Mask" "B.Paste")
			(net "P0V9_CPU1_RT_2D")
		)
		(pad "2" smd rect
			(at -3.199892 0 270)
			(size 2.413 2.8194)
			(layers "B.Cu" "B.Mask" "B.Paste")
			(net "GND")
		)
	)
)
